# BASEBOARD_FAB2 (Tioga Pass) — schematic netlist excerpt (pin names and nets, part order shuffled) for the footprints in the layout excerpt that follows; sources: Cadence DE-HDL packaged netlist, KiCad conversion of Wiwynn_Tioga_Pass_MB.brd

C4G9  CAP  1000PF 50V 10% X7R  pkg 0402LF  page 233 : A = PWRGD_PVPP_GHJ_R ; B = GND
C7G16  CAP  0.22UF 16V 10% X7R  pkg 0402  page 105 : A = P3E_CPU0_PE2_SS_TXN<10> ; B = P3E_CPU0_PE2_SS_C_TXN<10>
C7A33  CAP  47UF 4V 20% X6S  pkg 0805  page 132 : A = PVNN_PCH_STBY ; B = GND

(kicad_pcb
	(version 20260206)
	(generator "pcbnew")
	(generator_version "10.0")
	(general
		(thickness 1.6)
		(legacy_teardrops no)
	)
	(paper "A4")
	(title_block
		(title "Wiwynn_Tioga_Pass_MB.brd")
		(comment 1 "Tioga Pass / footprints 655-657 of 4770")
	)
	(layers
		(0 "F.Cu" signal "TOP")
		(4 "In1.Cu" signal "L2GND")
		(6 "In2.Cu" signal "L3")
		(8 "In3.Cu" signal "L4GND")
		(10 "In4.Cu" signal "L5")
		(12 "In5.Cu" signal "L6GND")
		(14 "In6.Cu" signal "L7VCC")
		(16 "In7.Cu" signal "L8VCC")
		(18 "In8.Cu" signal "L9GND")
		(20 "In9.Cu" signal "L10")
		(22 "In10.Cu" signal "L11GND")
		(24 "In11.Cu" signal "L12")
		(26 "In12.Cu" signal "L13GND")
		(2 "B.Cu" signal "BOTTOM")
		(9 "F.Adhes" user "F.Adhesive")
		(11 "B.Adhes" user "B.Adhesive")
		(13 "F.Paste" user "Package Geometry/Pastemask Top")
		(15 "B.Paste" user "Package Geometry/Pastemask Bottom")
		(5 "F.SilkS" user "Ref Des/Silkscreen Top")
		(7 "B.SilkS" user "Ref Des/Silkscreen Bottom")
		(1 "F.Mask" user "Board Geometry/Soldermask Top")
		(3 "B.Mask" user "Board Geometry/Soldermask Bottom")
		(17 "Dwgs.User" user "User.Drawings")
		(19 "Cmts.User" user "User.Comments")
		(21 "Eco1.User" user "User.Eco1")
		(23 "Eco2.User" user "User.Eco2")
		(25 "Edge.Cuts" user "Board Geometry/Outline")
		(27 "Margin" user)
		(31 "F.CrtYd" user "Package Geometry/Place Bound Top")
		(29 "B.CrtYd" user "Package Geometry/Place Bound Bottom")
		(35 "F.Fab" user "Ref Des/Assembly Top")
		(33 "B.Fab" user "Ref Des/Assembly Bottom")
	)
	(footprint ""
		(layer "F.Cu")
		(at 178.943 -8.1788)
		(property "Reference" "C4G9"
			(at 0 0 0)
			(layer "F.SilkS")
			(hide yes)
			(effects
				(font
					(size 1.27 1.27)
				)
			)
		)
		(property "Value" ""
			(at 0 0 0)
			(layer "F.Fab")
			(effects
				(font
					(size 1.27 1.27)
				)
			)
		)
		(duplicate_pad_numbers_are_jumpers no)
		(fp_rect
			(start -0.3048 0.9906)
			(end 0.3048 -0.1016)
			(stroke
				(width 0)
				(type default)
			)
			(fill no)
			(layer "F.CrtYd")
		)
		(fp_line
			(start -0.3048 -0.1016)
			(end -0.3048 0.9906)
			(stroke
				(width 0.1)
				(type default)
			)
			(layer "F.Fab")
		)
		(fp_line
			(start -0.3048 0.9906)
			(end 0.3048 0.9906)
			(stroke
				(width 0.1)
				(type default)
			)
			(layer "F.Fab")
		)
		(fp_line
			(start 0.3048 -0.1016)
			(end -0.3048 -0.1016)
			(stroke
				(width 0.1)
				(type default)
			)
			(layer "F.Fab")
		)
		(fp_line
			(start 0.3048 0.9906)
			(end 0.3048 -0.1016)
			(stroke
				(width 0.1)
				(type default)
			)
			(layer "F.Fab")
		)
		(pad "1" smd rect
			(at 0 0)
			(size 0.508 0.508)
			(layers "F.Cu" "F.Mask" "F.Paste")
			(net "PWRGD_PVPP_GHJ_R")
		)
		(pad "2" smd rect
			(at 0 0.889)
			(size 0.508 0.508)
			(layers "F.Cu" "F.Mask" "F.Paste")
			(net "GND")
		)
		(zone
			(layer "F.Cu")
			(hatch none 0.5)
			(connect_pads
				(clearance 0)
			)
			(min_thickness 0.25)
			(keepout
				(tracks allowed)
				(vias not_allowed)
				(pads allowed)
				(copperpour not_allowed)
				(footprints allowed)
			)
			(placement
				(enabled no)
				(sheetname "")
			)
			(fill
				(thermal_gap 0.5)
				(thermal_bridge_width 0.5)
				(island_removal_mode 0)
			)
			(polygon
				(pts
					(xy 178.689 -7.5438) (xy 179.197 -7.5438) (xy 179.197 -7.9248) (xy 178.689 -7.9248)
				)
			)
		)
		(zone
			(layer "F.Cu")
			(hatch none 0.5)
			(connect_pads
				(clearance 0)
			)
			(min_thickness 0.25)
			(keepout
				(tracks not_allowed)
				(vias allowed)
				(pads allowed)
				(copperpour not_allowed)
				(footprints allowed)
			)
			(placement
				(enabled no)
				(sheetname "")
			)
			(fill
				(thermal_gap 0.5)
				(thermal_bridge_width 0.5)
				(island_removal_mode 0)
			)
			(polygon
				(pts
					(xy 178.689 -7.5438) (xy 179.197 -7.5438) (xy 179.197 -7.9248) (xy 178.689 -7.9248)
				)
			)
		)
	)
	(footprint ""
		(layer "F.Cu")
		(at 374.4849 -136.9949)
		(property "Reference" "C7A33"
			(at 0 0 0)
			(layer "F.SilkS")
			(hide yes)
			(effects
				(font
					(size 1.27 1.27)
				)
			)
		)
		(property "Value" ""
			(at 0 0 0)
			(layer "F.Fab")
			(effects
				(font
					(size 1.27 1.27)
				)
			)
		)
		(duplicate_pad_numbers_are_jumpers no)
		(fp_rect
			(start -0.7239 1.9939)
			(end 0.7239 -0.2159)
			(stroke
				(width 0)
				(type default)
			)
			(fill no)
			(layer "F.CrtYd")
		)
		(fp_line
			(start -0.7239 -0.2159)
			(end -0.7239 1.9939)
			(stroke
				(width 0.1)
				(type default)
			)
			(layer "F.Fab")
		)
		(fp_line
			(start -0.7239 1.9939)
			(end 0.7239 1.9939)
			(stroke
				(width 0.1)
				(type default)
			)
			(layer "F.Fab")
		)
		(fp_line
			(start 0.7239 -0.2159)
			(end -0.7239 -0.2159)
			(stroke
				(width 0.1)
				(type default)
			)
			(layer "F.Fab")
		)
		(fp_line
			(start 0.7239 1.9939)
			(end 0.7239 -0.2159)
			(stroke
				(width 0.1)
				(type default)
			)
			(layer "F.Fab")
		)
		(pad "1" smd rect
			(at 0 0)
			(size 1.27 1.016)
			(layers "F.Cu" "F.Mask" "F.Paste")
			(net "PVNN_PCH_STBY")
		)
		(pad "2" smd rect
			(at 0 1.778)
			(size 1.27 1.016)
			(layers "F.Cu" "F.Mask" "F.Paste")
			(net "GND")
		)
		(zone
			(layer "F.Cu")
			(hatch none 0.5)
			(connect_pads
				(clearance 0)
			)
			(min_thickness 0.25)
			(keepout
				(tracks not_allowed)
				(vias allowed)
				(pads allowed)
				(copperpour not_allowed)
				(footprints allowed)
			)
			(placement
				(enabled no)
				(sheetname "")
			)
			(fill
				(thermal_gap 0.5)
				(thermal_bridge_width 0.5)
				(island_removal_mode 0)
			)
			(polygon
				(pts
					(xy 373.8499 -135.7249) (xy 375.1199 -135.7249) (xy 375.1199 -136.4869) (xy 373.8499 -136.4869)
				)
			)
		)
	)
	(footprint ""
		(layer "F.Cu")
		(at 375.167144 -10.916158)
		(property "Reference" "C7G16"
			(at 0 0 0)
			(layer "F.SilkS")
			(hide yes)
			(effects
				(font
					(size 1.27 1.27)
				)
			)
		)
		(property "Value" ""
			(at 0 0 0)
			(layer "F.Fab")
			(effects
				(font
					(size 1.27 1.27)
				)
			)
		)
		(duplicate_pad_numbers_are_jumpers no)
		(fp_rect
			(start -0.3048 0.9906)
			(end 0.3048 -0.1016)
			(stroke
				(width 0)
				(type default)
			)
			(fill no)
			(layer "F.CrtYd")
		)
		(fp_line
			(start -0.3048 -0.1016)
			(end -0.3048 0.9906)
			(stroke
				(width 0.1)
				(type default)
			)
			(layer "F.Fab")
		)
		(fp_line
			(start -0.3048 0.9906)
			(end 0.3048 0.9906)
			(stroke
				(width 0.1)
				(type default)
			)
			(layer "F.Fab")
		)
		(fp_line
			(start 0.3048 -0.1016)
			(end -0.3048 -0.1016)
			(stroke
				(width 0.1)
				(type default)
			)
			(layer "F.Fab")
		)
		(fp_line
			(start 0.3048 0.9906)
			(end 0.3048 -0.1016)
			(stroke
				(width 0.1)
				(type default)
			)
			(layer "F.Fab")
		)
		(pad "1" smd rect
			(at 0 0)
			(size 0.508 0.508)
			(layers "F.Cu" "F.Mask" "F.Paste")
			(net "P3E_CPU0_PE2_SS_TXN<10>")
		)
		(pad "2" smd rect
			(at 0 0.889)
			(size 0.508 0.508)
			(layers "F.Cu" "F.Mask" "F.Paste")
			(net "P3E_CPU0_PE2_SS_C_TXN<10>")
		)
		(zone
			(layer "F.Cu")
			(hatch none 0.5)
			(connect_pads
				(clearance 0)
			)
			(min_thickness 0.25)
			(keepout
				(tracks allowed)
				(vias not_allowed)
				(pads allowed)
				(copperpour not_allowed)
				(footprints allowed)
			)
			(placement
				(enabled no)
				(sheetname "")
			)
			(fill
				(thermal_gap 0.5)
				(thermal_bridge_width 0.5)
				(island_removal_mode 0)
			)
			(polygon
				(pts
					(xy 374.913144 -10.281158) (xy 375.421144 -10.281158) (xy 375.421144 -10.662158) (xy 374.913144 -10.662158)
				)
			)
		)
		(zone
			(layer "F.Cu")
			(hatch none 0.5)
			(connect_pads
				(clearance 0)
			)
			(min_thickness 0.25)
			(keepout
				(tracks not_allowed)
				(vias allowed)
				(pads allowed)
				(copperpour not_allowed)
				(footprints allowed)
			)
			(placement
				(enabled no)
				(sheetname "")
			)
			(fill
				(thermal_gap 0.5)
				(thermal_bridge_width 0.5)
				(island_removal_mode 0)
			)
			(polygon
				(pts
					(xy 374.913144 -10.281158) (xy 375.421144 -10.281158) (xy 375.421144 -10.662158) (xy 374.913144 -10.662158)
				)
			)
		)
	)
)
